# T6G (Grand Teton) — schematic netlist excerpt (pin names and nets, part order shuffled) for the footprints in the layout excerpt that follows; sources: Cadence DE-HDL packaged netlist, KiCad conversion of 04192023_DAF0TMB3IC0_F0TG_MB_C_brd_V02_OCP.brd

R1026  Q_RES  0 5% CHIP  pkg 0201LF  page 287 : A = SMB_RT_CPU0_P1_R_SDA ; B = SMB_RT_CPU0_P1_R2_SDA
C6674  Q_CAP_DIFFBUS  DIFF BUS_0.22UF 6.3V 20% X6S  pkg C0201  page 330 : \1\ = P5E_CPU1_P1_TX_BUF_C_DN<6> ; \2\ = P5E_CPU1_P1_TX_BUF_DN<6>
R3117  Q_RES  510K 5% EMPTY  pkg 0402LF  page 190 : A = P12V_AUX ; B = P3V3_AUX_EN

(kicad_pcb
	(version 20260206)
	(generator "pcbnew")
	(generator_version "10.0")
	(general
		(thickness 1.6)
		(legacy_teardrops no)
	)
	(paper "A4")
	(title_block
		(title "04192023_DAF0TMB3IC0_F0TG_MB_C_brd_V02_OCP.brd")
		(comment 1 "Grand Teton / footprints 7818-7820 of 8354")
	)
	(layers
		(0 "F.Cu" signal "TOP")
		(4 "In1.Cu" signal "GND")
		(6 "In2.Cu" signal "IN1")
		(8 "In3.Cu" signal "GND1")
		(10 "In4.Cu" signal "IN2")
		(12 "In5.Cu" signal "GND2")
		(14 "In6.Cu" signal "IN3")
		(16 "In7.Cu" signal "GND3")
		(18 "In8.Cu" signal "VCC")
		(20 "In9.Cu" signal "VCC1")
		(22 "In10.Cu" signal "GND4")
		(24 "In11.Cu" signal "IN4")
		(26 "In12.Cu" signal "GND5")
		(28 "In13.Cu" signal "IN5")
		(30 "In14.Cu" signal "GND6")
		(32 "In15.Cu" signal "IN6")
		(34 "In16.Cu" signal "GND7")
		(2 "B.Cu" signal "BOTTOM")
		(9 "F.Adhes" user "F.Adhesive")
		(11 "B.Adhes" user "B.Adhesive")
		(13 "F.Paste" user "Package Geometry/Pastemask Top")
		(15 "B.Paste" user "Package Geometry/Pastemask Bottom")
		(5 "F.SilkS" user "Ref Des/Silkscreen Top")
		(7 "B.SilkS" user "Ref Des/Silkscreen Bottom")
		(1 "F.Mask" user "Board Geometry/Soldermask Top")
		(3 "B.Mask" user "Board Geometry/Soldermask Bottom")
		(17 "Dwgs.User" user "User.Drawings")
		(19 "Cmts.User" user "User.Comments")
		(21 "Eco1.User" user "User.Eco1")
		(23 "Eco2.User" user "User.Eco2")
		(25 "Edge.Cuts" user "Board Geometry/Outline")
		(27 "Margin" user)
		(31 "F.CrtYd" user "Package Geometry/Place Bound Top")
		(29 "B.CrtYd" user "Package Geometry/Place Bound Bottom")
		(35 "F.Fab" user "Ref Des/Assembly Top")
		(33 "B.Fab" user "Ref Des/Assembly Bottom")
	)
	(footprint ""
		(layer "B.Cu")
		(at 456.690476 -45.978826 -90)
		(property "Reference" "R3117"
			(at 0 0 90)
			(layer "B.SilkS")
			(hide yes)
			(effects
				(font
					(size 1.27 1.27)
				)
				(justify mirror)
			)
		)
		(property "Value" ""
			(at 0 0 90)
			(layer "B.Fab")
			(effects
				(font
					(size 1.27 1.27)
				)
				(justify mirror)
			)
		)
		(duplicate_pad_numbers_are_jumpers no)
		(fp_line
			(start -0.7874 0.4064)
			(end 0.7874 0.4064)
			(stroke
				(width 0.1524)
				(type default)
			)
			(layer "B.SilkS")
		)
		(fp_line
			(start 0.7874 0.4064)
			(end 0.7874 -0.4064)
			(stroke
				(width 0.1524)
				(type default)
			)
			(layer "B.SilkS")
		)
		(fp_line
			(start -0.7874 -0.4064)
			(end -0.7874 0.4064)
			(stroke
				(width 0.1524)
				(type default)
			)
			(layer "B.SilkS")
		)
		(fp_line
			(start 0.7874 -0.4064)
			(end -0.7874 -0.4064)
			(stroke
				(width 0.1524)
				(type default)
			)
			(layer "B.SilkS")
		)
		(fp_line
			(start -0.67945 0.3048)
			(end -0.120396 0.3048)
			(stroke
				(width 0.1)
				(type default)
			)
			(layer "B.Fab")
		)
		(fp_line
			(start -0.120396 0.3048)
			(end -0.120396 0.2794)
			(stroke
				(width 0.1)
				(type default)
			)
			(layer "B.Fab")
		)
		(fp_line
			(start 0.12065 0.3048)
			(end 0.67945 0.3048)
			(stroke
				(width 0.1)
				(type default)
			)
			(layer "B.Fab")
		)
		(fp_line
			(start 0.67945 0.3048)
			(end 0.67945 -0.305054)
			(stroke
				(width 0.1)
				(type default)
			)
			(layer "B.Fab")
		)
		(fp_line
			(start -0.120396 0.2794)
			(end 0.12065 0.2794)
			(stroke
				(width 0.1)
				(type default)
			)
			(layer "B.Fab")
		)
		(fp_line
			(start 0.12065 0.2794)
			(end 0.12065 0.3048)
			(stroke
				(width 0.1)
				(type default)
			)
			(layer "B.Fab")
		)
		(fp_line
			(start -0.12065 -0.2794)
			(end -0.12065 -0.3048)
			(stroke
				(width 0.1)
				(type default)
			)
			(layer "B.Fab")
		)
		(fp_line
			(start 0.12065 -0.2794)
			(end -0.12065 -0.2794)
			(stroke
				(width 0.1)
				(type default)
			)
			(layer "B.Fab")
		)
		(fp_line
			(start -0.67945 -0.3048)
			(end -0.67945 0.3048)
			(stroke
				(width 0.1)
				(type default)
			)
			(layer "B.Fab")
		)
		(fp_line
			(start -0.12065 -0.3048)
			(end -0.67945 -0.3048)
			(stroke
				(width 0.1)
				(type default)
			)
			(layer "B.Fab")
		)
		(fp_line
			(start 0.12065 -0.305054)
			(end 0.12065 -0.2794)
			(stroke
				(width 0.1)
				(type default)
			)
			(layer "B.Fab")
		)
		(fp_line
			(start 0.67945 -0.305054)
			(end 0.12065 -0.305054)
			(stroke
				(width 0.1)
				(type default)
			)
			(layer "B.Fab")
		)
		(pad "1" smd circle
			(at 0.40005 0 90)
			(size 0 0)
			(layers "B.Cu" "B.Mask" "B.Paste")
			(net "P12V_AUX")
		)
		(pad "2" smd circle
			(at -0.40005 0 90)
			(size 0 0)
			(layers "B.Cu" "B.Mask" "B.Paste")
			(net "P3V3_AUX_EN")
		)
	)
	(footprint ""
		(layer "B.Cu")
		(at 67.679824 -408.517344 90)
		(property "Reference" "C6674"
			(at 0 0 90)
			(layer "B.SilkS")
			(hide yes)
			(effects
				(font
					(size 1.27 1.27)
				)
				(justify mirror)
			)
		)
		(property "Value" ""
			(at 0 0 90)
			(layer "B.Fab")
			(effects
				(font
					(size 1.27 1.27)
				)
				(justify mirror)
			)
		)
		(duplicate_pad_numbers_are_jumpers no)
		(fp_line
			(start 0.299974 -0.150114)
			(end -0.299974 -0.150114)
			(stroke
				(width 0.1)
				(type default)
			)
			(layer "B.Fab")
		)
		(fp_line
			(start -0.299974 -0.150114)
			(end -0.299974 0.150114)
			(stroke
				(width 0.1)
				(type default)
			)
			(layer "B.Fab")
		)
		(fp_line
			(start 0.299974 0.150114)
			(end 0.299974 -0.150114)
			(stroke
				(width 0.1)
				(type default)
			)
			(layer "B.Fab")
		)
		(fp_line
			(start -0.299974 0.150114)
			(end 0.299974 0.150114)
			(stroke
				(width 0.1)
				(type default)
			)
			(layer "B.Fab")
		)
		(pad "1" smd rect
			(at 0.2667 0 270)
			(size 0.3048 0.381)
			(layers "B.Cu" "B.Mask" "B.Paste")
			(net "P5E_CPU1_P1_TX_BUF_C_DN<6>")
		)
		(pad "2" smd rect
			(at -0.2667 0 270)
			(size 0.3048 0.381)
			(layers "B.Cu" "B.Mask" "B.Paste")
			(net "P5E_CPU1_P1_TX_BUF_DN<6>")
		)
	)
	(footprint ""
		(layer "B.Cu")
		(at 233.807 -339.598 180)
		(property "Reference" "R1026"
			(at 0 0 0)
			(layer "B.SilkS")
			(hide yes)
			(effects
				(font
					(size 1.27 1.27)
				)
				(justify mirror)
			)
		)
		(property "Value" ""
			(at 0 0 0)
			(layer "B.Fab")
			(effects
				(font
					(size 1.27 1.27)
				)
				(justify mirror)
			)
		)
		(duplicate_pad_numbers_are_jumpers no)
		(fp_line
			(start 0.32512 0.175006)
			(end 0.32512 -0.175006)
			(stroke
				(width 0.1)
				(type default)
			)
			(layer "B.Fab")
		)
		(fp_line
			(start 0.32512 -0.175006)
			(end -0.32512 -0.175006)
			(stroke
				(width 0.1)
				(type default)
			)
			(layer "B.Fab")
		)
		(fp_line
			(start -0.32512 0.175006)
			(end 0.32512 0.175006)
			(stroke
				(width 0.1)
				(type default)
			)
			(layer "B.Fab")
		)
		(fp_line
			(start -0.32512 -0.175006)
			(end -0.32512 0.175006)
			(stroke
				(width 0.1)
				(type default)
			)
			(layer "B.Fab")
		)
		(pad "1" smd rect
			(at 0.2667 0)
			(size 0.3048 0.381)
			(layers "B.Cu" "B.Mask" "B.Paste")
			(net "SMB_RT_CPU0_P1_R_SDA")
		)
		(pad "2" smd rect
			(at -0.2667 0 180)
			(size 0.3048 0.381)
			(layers "B.Cu" "B.Mask" "B.Paste")
			(net "SMB_RT_CPU0_P1_R2_SDA")
		)
	)
)
